# S9S_MB_2U (Grand Teton) — schematic netlist excerpt (pin names and nets, part order shuffled) for the footprints in the layout excerpt that follows; sources: Cadence DE-HDL packaged netlist, KiCad conversion of 03242023_DA0F0TMBIJ0_F0T_Motherboard_J_brd_V01_OCP.brd

R1823  Q_RES  1K 1% CHIP  pkg 0402LF  page 216 : A = P3V3_AUX ; B = RST_MB_STBY_R_N
PR3937  Q_RES  120K 1% CHIP  pkg 0402LF  page 301 : A = HSC_MODE ; B = AGND_HSC

(kicad_pcb
	(version 20260206)
	(generator "pcbnew")
	(generator_version "10.0")
	(general
		(thickness 1.6)
		(legacy_teardrops no)
	)
	(paper "A4")
	(title_block
		(title "03242023_DA0F0TMBIJ0_F0T_Motherboard_J_brd_V01_OCP.brd")
		(comment 1 "Grand Teton / footprints 1635-1636 of 6105")
	)
	(layers
		(0 "F.Cu" signal "TOP")
		(4 "In1.Cu" signal "GND")
		(6 "In2.Cu" signal "IN1")
		(8 "In3.Cu" signal "GND1")
		(10 "In4.Cu" signal "IN2")
		(12 "In5.Cu" signal "GND2")
		(14 "In6.Cu" signal "IN3")
		(16 "In7.Cu" signal "GND3")
		(18 "In8.Cu" signal "VCC")
		(20 "In9.Cu" signal "VCC1")
		(22 "In10.Cu" signal "GND4")
		(24 "In11.Cu" signal "IN4")
		(26 "In12.Cu" signal "GND5")
		(28 "In13.Cu" signal "IN5")
		(30 "In14.Cu" signal "GND6")
		(32 "In15.Cu" signal "IN6")
		(34 "In16.Cu" signal "GND7")
		(2 "B.Cu" signal "BOTTOM")
		(9 "F.Adhes" user "F.Adhesive")
		(11 "B.Adhes" user "B.Adhesive")
		(13 "F.Paste" user "Package Geometry/Pastemask Top")
		(15 "B.Paste" user "Package Geometry/Pastemask Bottom")
		(5 "F.SilkS" user "Ref Des/Silkscreen Top")
		(7 "B.SilkS" user "Ref Des/Silkscreen Bottom")
		(1 "F.Mask" user "Board Geometry/Soldermask Top")
		(3 "B.Mask" user "Board Geometry/Soldermask Bottom")
		(17 "Dwgs.User" user "User.Drawings")
		(19 "Cmts.User" user "User.Comments")
		(21 "Eco1.User" user "User.Eco1")
		(23 "Eco2.User" user "User.Eco2")
		(25 "Edge.Cuts" user "Board Geometry/Outline")
		(27 "Margin" user)
		(31 "F.CrtYd" user "Package Geometry/Place Bound Top")
		(29 "B.CrtYd" user "Package Geometry/Place Bound Bottom")
		(35 "F.Fab" user "Ref Des/Assembly Top")
		(33 "B.Fab" user "Ref Des/Assembly Bottom")
	)
	(footprint ""
		(layer "F.Cu")
		(at 193.60388 -104.955848 180)
		(property "Reference" "R1823"
			(at 0 0 180)
			(layer "F.SilkS")
			(hide yes)
			(effects
				(font
					(size 1.27 1.27)
				)
			)
		)
		(property "Value" ""
			(at 0 0 180)
			(layer "F.Fab")
			(effects
				(font
					(size 1.27 1.27)
				)
			)
		)
		(duplicate_pad_numbers_are_jumpers no)
		(fp_line
			(start 0.7874 0.4064)
			(end -0.7874 0.4064)
			(stroke
				(width 0.1524)
				(type default)
			)
			(layer "F.SilkS")
		)
		(fp_line
			(start 0.7874 -0.4064)
			(end 0.7874 0.4064)
			(stroke
				(width 0.1524)
				(type default)
			)
			(layer "F.SilkS")
		)
		(fp_line
			(start -0.7874 0.4064)
			(end -0.7874 -0.4064)
			(stroke
				(width 0.1524)
				(type default)
			)
			(layer "F.SilkS")
		)
		(fp_line
			(start -0.7874 -0.4064)
			(end 0.7874 -0.4064)
			(stroke
				(width 0.1524)
				(type default)
			)
			(layer "F.SilkS")
		)
		(fp_line
			(start 0.67945 0.3048)
			(end 0.120396 0.3048)
			(stroke
				(width 0.1)
				(type default)
			)
			(layer "F.Fab")
		)
		(fp_line
			(start 0.67945 -0.3048)
			(end 0.67945 0.3048)
			(stroke
				(width 0.1)
				(type default)
			)
			(layer "F.Fab")
		)
		(fp_line
			(start 0.12065 -0.2794)
			(end 0.12065 -0.3048)
			(stroke
				(width 0.1)
				(type default)
			)
			(layer "F.Fab")
		)
		(fp_line
			(start 0.12065 -0.3048)
			(end 0.67945 -0.3048)
			(stroke
				(width 0.1)
				(type default)
			)
			(layer "F.Fab")
		)
		(fp_line
			(start 0.120396 0.3048)
			(end 0.120396 0.2794)
			(stroke
				(width 0.1)
				(type default)
			)
			(layer "F.Fab")
		)
		(fp_line
			(start 0.120396 0.2794)
			(end -0.12065 0.2794)
			(stroke
				(width 0.1)
				(type default)
			)
			(layer "F.Fab")
		)
		(fp_line
			(start -0.12065 0.3048)
			(end -0.67945 0.3048)
			(stroke
				(width 0.1)
				(type default)
			)
			(layer "F.Fab")
		)
		(fp_line
			(start -0.12065 0.2794)
			(end -0.12065 0.3048)
			(stroke
				(width 0.1)
				(type default)
			)
			(layer "F.Fab")
		)
		(fp_line
			(start -0.12065 -0.2794)
			(end 0.12065 -0.2794)
			(stroke
				(width 0.1)
				(type default)
			)
			(layer "F.Fab")
		)
		(fp_line
			(start -0.12065 -0.305054)
			(end -0.12065 -0.2794)
			(stroke
				(width 0.1)
				(type default)
			)
			(layer "F.Fab")
		)
		(fp_line
			(start -0.67945 0.3048)
			(end -0.67945 -0.305054)
			(stroke
				(width 0.1)
				(type default)
			)
			(layer "F.Fab")
		)
		(fp_line
			(start -0.67945 -0.305054)
			(end -0.12065 -0.305054)
			(stroke
				(width 0.1)
				(type default)
			)
			(layer "F.Fab")
		)
		(pad "1" smd circle
			(at -0.40005 0 180)
			(size 0 0)
			(layers "F.Cu" "F.Mask" "F.Paste")
			(net "P3V3_AUX")
		)
		(pad "2" smd circle
			(at 0.40005 0 180)
			(size 0 0)
			(layers "F.Cu" "F.Mask" "F.Paste")
			(net "RST_MB_STBY_R_N")
		)
	)
	(footprint ""
		(layer "F.Cu")
		(at 192.052448 -404.414482)
		(property "Reference" "PR3937"
			(at 0 0 0)
			(layer "F.SilkS")
			(hide yes)
			(effects
				(font
					(size 1.27 1.27)
				)
			)
		)
		(property "Value" ""
			(at 0 0 0)
			(layer "F.Fab")
			(effects
				(font
					(size 1.27 1.27)
				)
			)
		)
		(duplicate_pad_numbers_are_jumpers no)
		(fp_line
			(start -0.7874 -0.4064)
			(end 0.7874 -0.4064)
			(stroke
				(width 0.1524)
				(type default)
			)
			(layer "F.SilkS")
		)
		(fp_line
			(start -0.7874 0.4064)
			(end -0.7874 -0.4064)
			(stroke
				(width 0.1524)
				(type default)
			)
			(layer "F.SilkS")
		)
		(fp_line
			(start 0.7874 -0.4064)
			(end 0.7874 0.4064)
			(stroke
				(width 0.1524)
				(type default)
			)
			(layer "F.SilkS")
		)
		(fp_line
			(start 0.7874 0.4064)
			(end -0.7874 0.4064)
			(stroke
				(width 0.1524)
				(type default)
			)
			(layer "F.SilkS")
		)
		(fp_line
			(start -0.67945 -0.305054)
			(end -0.12065 -0.305054)
			(stroke
				(width 0.1)
				(type default)
			)
			(layer "F.Fab")
		)
		(fp_line
			(start -0.67945 0.3048)
			(end -0.67945 -0.305054)
			(stroke
				(width 0.1)
				(type default)
			)
			(layer "F.Fab")
		)
		(fp_line
			(start -0.12065 -0.305054)
			(end -0.12065 -0.2794)
			(stroke
				(width 0.1)
				(type default)
			)
			(layer "F.Fab")
		)
		(fp_line
			(start -0.12065 -0.2794)
			(end 0.12065 -0.2794)
			(stroke
				(width 0.1)
				(type default)
			)
			(layer "F.Fab")
		)
		(fp_line
			(start -0.12065 0.2794)
			(end -0.12065 0.3048)
			(stroke
				(width 0.1)
				(type default)
			)
			(layer "F.Fab")
		)
		(fp_line
			(start -0.12065 0.3048)
			(end -0.67945 0.3048)
			(stroke
				(width 0.1)
				(type default)
			)
			(layer "F.Fab")
		)
		(fp_line
			(start 0.120396 0.2794)
			(end -0.12065 0.2794)
			(stroke
				(width 0.1)
				(type default)
			)
			(layer "F.Fab")
		)
		(fp_line
			(start 0.120396 0.3048)
			(end 0.120396 0.2794)
			(stroke
				(width 0.1)
				(type default)
			)
			(layer "F.Fab")
		)
		(fp_line
			(start 0.12065 -0.3048)
			(end 0.67945 -0.3048)
			(stroke
				(width 0.1)
				(type default)
			)
			(layer "F.Fab")
		)
		(fp_line
			(start 0.12065 -0.2794)
			(end 0.12065 -0.3048)
			(stroke
				(width 0.1)
				(type default)
			)
			(layer "F.Fab")
		)
		(fp_line
			(start 0.67945 -0.3048)
			(end 0.67945 0.3048)
			(stroke
				(width 0.1)
				(type default)
			)
			(layer "F.Fab")
		)
		(fp_line
			(start 0.67945 0.3048)
			(end 0.120396 0.3048)
			(stroke
				(width 0.1)
				(type default)
			)
			(layer "F.Fab")
		)
		(pad "1" smd circle
			(at -0.40005 0)
			(size 0 0)
			(layers "F.Cu" "F.Mask" "F.Paste")
			(net "HSC_MODE")
		)
		(pad "2" smd circle
			(at 0.40005 0)
			(size 0 0)
			(layers "F.Cu" "F.Mask" "F.Paste")
			(net "AGND_HSC")
		)
	)
)
